(kicad_pcb
	(version 20260206)
	(generator "pcbnew")
	(generator_version "10.0")
	(general
		(thickness 1.6)
		(legacy_teardrops no)
	)
	(paper "A4")
	(title_block
		(title "baseboard — 13948-1b.1110WZS1818.brd")
		(comment 1 "Honey Badger (Wiwynn) / footprints 790-796 of 2523")
	)
	(layers
		(0 "F.Cu" signal "TOP")
		(4 "In1.Cu" signal "L2GND")
		(6 "In2.Cu" signal "L3")
		(8 "In3.Cu" signal "L4VCC")
		(10 "In4.Cu" signal "L5VCC")
		(12 "In5.Cu" signal "L6")
		(14 "In6.Cu" signal "L7GND")
		(2 "B.Cu" signal "BOTTOM")
		(9 "F.Adhes" user "F.Adhesive")
		(11 "B.Adhes" user "B.Adhesive")
		(13 "F.Paste" user "Package Geometry/Pastemask Top")
		(15 "B.Paste" user "Package Geometry/Pastemask Bottom")
		(5 "F.SilkS" user "Ref Des/Silkscreen Top")
		(7 "B.SilkS" user "Ref Des/Silkscreen Bottom")
		(1 "F.Mask" user "Board Geometry/Soldermask Top")
		(3 "B.Mask" user "Board Geometry/Soldermask Bottom")
		(17 "Dwgs.User" user "User.Drawings")
		(19 "Cmts.User" user "User.Comments")
		(21 "Eco1.User" user "User.Eco1")
		(23 "Eco2.User" user "User.Eco2")
		(25 "Edge.Cuts" user "Board Geometry/Outline")
		(27 "Margin" user)
		(31 "F.CrtYd" user "Package Geometry/Place Bound Top")
		(29 "B.CrtYd" user "Package Geometry/Place Bound Bottom")
		(35 "F.Fab" user "Ref Des/Assembly Top")
		(33 "B.Fab" user "Ref Des/Assembly Bottom")
	)
	(footprint ""
		(layer "F.Cu")
		(at 36.83 -169.291 -90)
		(property "Reference" "R805"
			(at 0 0 270)
			(layer "F.SilkS")
			(hide yes)
			(effects
				(font
					(size 1.27 1.27)
				)
			)
		)
		(property "Value" "0R2J-2-GP"
			(at 0.064008 -3.993896 270)
			(unlocked yes)
			(layer "F.Fab")
			(hide yes)
			(effects
				(font
					(size 1.016 1.016)
					(thickness 0.1524)
				)
			)
		)
		(property "Device Type" "R402H16"
			(at 0.064008 -5.517896 270)
			(unlocked yes)
			(layer "F.Fab")
			(hide yes)
			(effects
				(font
					(size 1.016 1.016)
					(thickness 0.1524)
				)
			)
		)
		(duplicate_pad_numbers_are_jumpers no)
		(fp_line
			(start -0.508 -0.9398)
			(end -0.508 0.9398)
			(stroke
				(width 0.1524)
				(type default)
			)
			(layer "F.SilkS")
		)
		(fp_line
			(start 0.508 -0.9398)
			(end -0.508 -0.9398)
			(stroke
				(width 0.1524)
				(type default)
			)
			(layer "F.SilkS")
		)
		(fp_rect
			(start -0.508 0.9398)
			(end 0.508 -0.9398)
			(stroke
				(width 0)
				(type default)
			)
			(fill no)
			(layer "F.CrtYd")
		)
		(fp_rect
			(start -0.508 0.9398)
			(end 0.508 -0.9398)
			(stroke
				(width 0)
				(type default)
			)
			(fill no)
			(layer "F.Fab")
		)
		(pad "1" smd custom
			(at 0 -0.4445 270)
			(size 0.1397 0.1397)
			(layers "F.Cu" "F.Mask" "F.Paste")
			(net "DP_BMC_EXP_RST_N_R")
			(options
				(clearance outline)
				(anchor circle)
			)
			(primitives
				(gr_poly
					(pts
						(arc
							(start -0.1778 -0.2794)
							(mid -0.249642 -0.249642)
							(end -0.2794 -0.1778)
						)
						(arc
							(start -0.2794 0.1778)
							(mid -0.249642 0.249642)
							(end -0.1778 0.2794)
						)
						(arc
							(start 0.1778 0.2794)
							(mid 0.249642 0.249642)
							(end 0.2794 0.1778)
						)
						(arc
							(start 0.2794 -0.1778)
							(mid 0.249642 -0.249642)
							(end 0.1778 -0.2794)
						)
					)
					(width 0)
					(fill yes)
				)
			)
		)
		(pad "2" smd custom
			(at 0 0.4445 270)
			(size 0.1397 0.1397)
			(layers "F.Cu" "F.Mask" "F.Paste")
			(net "DP_BMC_EXP_RST_N")
			(options
				(clearance outline)
				(anchor circle)
			)
			(primitives
				(gr_poly
					(pts
						(arc
							(start -0.1778 -0.2794)
							(mid -0.249642 -0.249642)
							(end -0.2794 -0.1778)
						)
						(arc
							(start -0.2794 0.1778)
							(mid -0.249642 0.249642)
							(end -0.1778 0.2794)
						)
						(arc
							(start 0.1778 0.2794)
							(mid 0.249642 0.249642)
							(end 0.2794 0.1778)
						)
						(arc
							(start 0.2794 -0.1778)
							(mid 0.249642 -0.249642)
							(end 0.1778 -0.2794)
						)
					)
					(width 0)
					(fill yes)
				)
			)
		)
	)
	(footprint ""
		(layer "F.Cu")
		(at 314.4774 -212.7504)
		(property "Reference" "U179"
			(at 0 0 0)
			(layer "F.SilkS")
			(hide yes)
			(effects
				(font
					(size 1.27 1.27)
				)
			)
		)
		(property "Value" "SNLVC1G126DCKR-GP"
			(at -2.3368 -8.6868 0)
			(unlocked yes)
			(layer "F.Fab")
			(hide yes)
			(effects
				(font
					(size 1.016 1.016)
					(thickness 0.1524)
				)
			)
		)
		(property "Device Type" "SC70-5H44"
			(at -2.3114 -10.414 0)
			(unlocked yes)
			(layer "F.Fab")
			(hide yes)
			(effects
				(font
					(size 1.016 1.016)
					(thickness 0.1524)
				)
			)
		)
		(duplicate_pad_numbers_are_jumpers no)
		(fp_line
			(start -1.27 -1.7018)
			(end 1.27 -1.7018)
			(stroke
				(width 0.1524)
				(type default)
			)
			(layer "F.SilkS")
		)
		(fp_line
			(start -1.27 1.7018)
			(end -1.27 -1.7018)
			(stroke
				(width 0.1524)
				(type default)
			)
			(layer "F.SilkS")
		)
		(fp_line
			(start 0.6604 -1.8034)
			(end 1.3843 -1.8034)
			(stroke
				(width 0.3302)
				(type default)
			)
			(layer "F.SilkS")
		)
		(fp_line
			(start 1.27 -1.7018)
			(end 1.27 1.7018)
			(stroke
				(width 0.1524)
				(type default)
			)
			(layer "F.SilkS")
		)
		(fp_line
			(start 1.27 1.7018)
			(end -1.27 1.7018)
			(stroke
				(width 0.1524)
				(type default)
			)
			(layer "F.SilkS")
		)
		(fp_line
			(start 1.3843 -1.8034)
			(end 1.3843 -1.1176)
			(stroke
				(width 0.3302)
				(type default)
			)
			(layer "F.SilkS")
		)
		(fp_rect
			(start -1.524 1.9558)
			(end 1.524 -1.9558)
			(stroke
				(width 0)
				(type default)
			)
			(fill no)
			(layer "F.CrtYd")
		)
		(fp_poly
			(pts
				(xy -1.524 -1.9558) (xy 1.524 -1.9558) (xy 1.524 1.9558) (xy -1.524 1.9558)
			)
			(stroke
				(width 0)
				(type default)
			)
			(fill no)
			(layer "F.Fab")
		)
		(pad "1" smd rect
			(at 0.65024 -0.8255)
			(size 0.4064 1.2192)
			(layers "F.Cu" "F.Mask" "F.Paste")
			(net "EXP_TDO_EN")
		)
		(pad "2" smd rect
			(at 0 -0.8255)
			(size 0.4064 1.2192)
			(layers "F.Cu" "F.Mask" "F.Paste")
			(net "JTAG_EXP_R_TDO")
		)
		(pad "3" smd rect
			(at -0.65024 -0.8255)
			(size 0.4064 1.2192)
			(layers "F.Cu" "F.Mask" "F.Paste")
			(net "GND")
		)
		(pad "4" smd rect
			(at -0.65024 0.8255)
			(size 0.4064 1.2192)
			(layers "F.Cu" "F.Mask" "F.Paste")
			(net "JTAG_IOC_L_TDI_R")
		)
		(pad "5" smd rect
			(at 0.65024 0.8255)
			(size 0.4064 1.2192)
			(layers "F.Cu" "F.Mask" "F.Paste")
			(net "P1V8_STBY")
		)
	)
	(footprint ""
		(layer "F.Cu")
		(at 277.866094 -25.791668)
		(property "Reference" "R409"
			(at 0 0 0)
			(layer "F.SilkS")
			(hide yes)
			(effects
				(font
					(size 1.27 1.27)
				)
			)
		)
		(property "Value" "0R2J-2-GP"
			(at 0.064008 -3.993896 0)
			(unlocked yes)
			(layer "F.Fab")
			(hide yes)
			(effects
				(font
					(size 1.016 1.016)
					(thickness 0.1524)
				)
			)
		)
		(property "Device Type" "R402H16"
			(at 0.064008 -5.517896 0)
			(unlocked yes)
			(layer "F.Fab")
			(hide yes)
			(effects
				(font
					(size 1.016 1.016)
					(thickness 0.1524)
				)
			)
		)
		(duplicate_pad_numbers_are_jumpers no)
		(fp_line
			(start -0.508 -0.9398)
			(end -0.508 0.9398)
			(stroke
				(width 0.1524)
				(type default)
			)
			(layer "F.SilkS")
		)
		(fp_line
			(start 0.508 -0.9398)
			(end -0.508 -0.9398)
			(stroke
				(width 0.1524)
				(type default)
			)
			(layer "F.SilkS")
		)
		(fp_rect
			(start -0.508 0.9398)
			(end 0.508 -0.9398)
			(stroke
				(width 0)
				(type default)
			)
			(fill no)
			(layer "F.CrtYd")
		)
		(fp_rect
			(start -0.508 0.9398)
			(end 0.508 -0.9398)
			(stroke
				(width 0)
				(type default)
			)
			(fill no)
			(layer "F.Fab")
		)
		(pad "1" smd custom
			(at 0 -0.4445)
			(size 0.1397 0.1397)
			(layers "F.Cu" "F.Mask" "F.Paste")
			(net "USB_DP_R")
			(options
				(clearance outline)
				(anchor circle)
			)
			(primitives
				(gr_poly
					(pts
						(arc
							(start -0.1778 -0.2794)
							(mid -0.249642 -0.249642)
							(end -0.2794 -0.1778)
						)
						(arc
							(start -0.2794 0.1778)
							(mid -0.249642 0.249642)
							(end -0.1778 0.2794)
						)
						(arc
							(start 0.1778 0.2794)
							(mid 0.249642 0.249642)
							(end 0.2794 0.1778)
						)
						(arc
							(start 0.2794 -0.1778)
							(mid 0.249642 -0.249642)
							(end 0.1778 -0.2794)
						)
					)
					(width 0)
					(fill yes)
				)
			)
		)
		(pad "2" smd custom
			(at 0 0.4445)
			(size 0.1397 0.1397)
			(layers "F.Cu" "F.Mask" "F.Paste")
			(net "USB_P1_F_DP1")
			(options
				(clearance outline)
				(anchor circle)
			)
			(primitives
				(gr_poly
					(pts
						(arc
							(start -0.1778 -0.2794)
							(mid -0.249642 -0.249642)
							(end -0.2794 -0.1778)
						)
						(arc
							(start -0.2794 0.1778)
							(mid -0.249642 0.249642)
							(end -0.1778 0.2794)
						)
						(arc
							(start 0.1778 0.2794)
							(mid 0.249642 0.249642)
							(end 0.2794 0.1778)
						)
						(arc
							(start 0.2794 -0.1778)
							(mid 0.249642 -0.249642)
							(end 0.1778 -0.2794)
						)
					)
					(width 0)
					(fill yes)
				)
			)
		)
	)
	(footprint ""
		(layer "F.Cu")
		(at 66.715386 -110.408212 -90)
		(property "Reference" "PR167"
			(at 0 0 270)
			(layer "F.SilkS")
			(hide yes)
			(effects
				(font
					(size 1.27 1.27)
				)
			)
		)
		(property "Value" "4K02R2F-GP"
			(at 0.064008 -3.993896 270)
			(unlocked yes)
			(layer "F.Fab")
			(hide yes)
			(effects
				(font
					(size 1.016 1.016)
					(thickness 0.1524)
				)
			)
		)
		(property "Device Type" "R402H16"
			(at 0.064008 -5.517896 270)
			(unlocked yes)
			(layer "F.Fab")
			(hide yes)
			(effects
				(font
					(size 1.016 1.016)
					(thickness 0.1524)
				)
			)
		)
		(duplicate_pad_numbers_are_jumpers no)
		(fp_line
			(start -0.508 -0.9398)
			(end -0.508 0.9398)
			(stroke
				(width 0.1524)
				(type default)
			)
			(layer "F.SilkS")
		)
		(fp_line
			(start 0.508 -0.9398)
			(end -0.508 -0.9398)
			(stroke
				(width 0.1524)
				(type default)
			)
			(layer "F.SilkS")
		)
		(fp_rect
			(start -0.508 0.9398)
			(end 0.508 -0.9398)
			(stroke
				(width 0)
				(type default)
			)
			(fill no)
			(layer "F.CrtYd")
		)
		(fp_rect
			(start -0.508 0.9398)
			(end 0.508 -0.9398)
			(stroke
				(width 0)
				(type default)
			)
			(fill no)
			(layer "F.Fab")
		)
		(pad "1" smd custom
			(at 0 -0.4445 270)
			(size 0.1397 0.1397)
			(layers "F.Cu" "F.Mask" "F.Paste")
			(net "P1V8_EN_G")
			(options
				(clearance outline)
				(anchor circle)
			)
			(primitives
				(gr_poly
					(pts
						(arc
							(start -0.1778 -0.2794)
							(mid -0.249642 -0.249642)
							(end -0.2794 -0.1778)
						)
						(arc
							(start -0.2794 0.1778)
							(mid -0.249642 0.249642)
							(end -0.1778 0.2794)
						)
						(arc
							(start 0.1778 0.2794)
							(mid 0.249642 0.249642)
							(end 0.2794 0.1778)
						)
						(arc
							(start 0.2794 -0.1778)
							(mid 0.249642 -0.249642)
							(end 0.1778 -0.2794)
						)
					)
					(width 0)
					(fill yes)
				)
			)
		)
		(pad "2" smd custom
			(at 0 0.4445 270)
			(size 0.1397 0.1397)
			(layers "F.Cu" "F.Mask" "F.Paste")
			(net "P3V3_STBY")
			(options
				(clearance outline)
				(anchor circle)
			)
			(primitives
				(gr_poly
					(pts
						(arc
							(start -0.1778 -0.2794)
							(mid -0.249642 -0.249642)
							(end -0.2794 -0.1778)
						)
						(arc
							(start -0.2794 0.1778)
							(mid -0.249642 0.249642)
							(end -0.1778 0.2794)
						)
						(arc
							(start 0.1778 0.2794)
							(mid 0.249642 0.249642)
							(end 0.2794 0.1778)
						)
						(arc
							(start 0.2794 -0.1778)
							(mid 0.249642 -0.249642)
							(end 0.1778 -0.2794)
						)
					)
					(width 0)
					(fill yes)
				)
			)
		)
	)
	(footprint ""
		(layer "F.Cu")
		(at 50.546 -224.917)
		(property "Reference" "R2106"
			(at 0 0 0)
			(layer "F.SilkS")
			(hide yes)
			(effects
				(font
					(size 1.27 1.27)
				)
			)
		)
		(property "Value" "49K9R2F-L-GP"
			(at 0.064008 -3.993896 0)
			(unlocked yes)
			(layer "F.Fab")
			(hide yes)
			(effects
				(font
					(size 1.016 1.016)
					(thickness 0.1524)
				)
			)
		)
		(property "Device Type" "R402H16"
			(at 0.064008 -5.517896 0)
			(unlocked yes)
			(layer "F.Fab")
			(hide yes)
			(effects
				(font
					(size 1.016 1.016)
					(thickness 0.1524)
				)
			)
		)
		(duplicate_pad_numbers_are_jumpers no)
		(fp_line
			(start -0.508 -0.9398)
			(end -0.508 0.9398)
			(stroke
				(width 0.1524)
				(type default)
			)
			(layer "F.SilkS")
		)
		(fp_line
			(start 0.508 -0.9398)
			(end -0.508 -0.9398)
			(stroke
				(width 0.1524)
				(type default)
			)
			(layer "F.SilkS")
		)
		(fp_rect
			(start -0.508 0.9398)
			(end 0.508 -0.9398)
			(stroke
				(width 0)
				(type default)
			)
			(fill no)
			(layer "F.CrtYd")
		)
		(fp_rect
			(start -0.508 0.9398)
			(end 0.508 -0.9398)
			(stroke
				(width 0)
				(type default)
			)
			(fill no)
			(layer "F.Fab")
		)
		(pad "1" smd custom
			(at 0 -0.4445)
			(size 0.1397 0.1397)
			(layers "F.Cu" "F.Mask" "F.Paste")
			(net "P12V_PCIE")
			(options
				(clearance outline)
				(anchor circle)
			)
			(primitives
				(gr_poly
					(pts
						(arc
							(start -0.1778 -0.2794)
							(mid -0.249642 -0.249642)
							(end -0.2794 -0.1778)
						)
						(arc
							(start -0.2794 0.1778)
							(mid -0.249642 0.249642)
							(end -0.1778 0.2794)
						)
						(arc
							(start 0.1778 0.2794)
							(mid 0.249642 0.249642)
							(end 0.2794 0.1778)
						)
						(arc
							(start 0.2794 -0.1778)
							(mid 0.249642 -0.249642)
							(end 0.1778 -0.2794)
						)
					)
					(width 0)
					(fill yes)
				)
			)
		)
		(pad "2" smd custom
			(at 0 0.4445)
			(size 0.1397 0.1397)
			(layers "F.Cu" "F.Mask" "F.Paste")
			(net "MB0_CM_OV_R")
			(options
				(clearance outline)
				(anchor circle)
			)
			(primitives
				(gr_poly
					(pts
						(arc
							(start -0.1778 -0.2794)
							(mid -0.249642 -0.249642)
							(end -0.2794 -0.1778)
						)
						(arc
							(start -0.2794 0.1778)
							(mid -0.249642 0.249642)
							(end -0.1778 0.2794)
						)
						(arc
							(start 0.1778 0.2794)
							(mid 0.249642 0.249642)
							(end 0.2794 0.1778)
						)
						(arc
							(start 0.2794 -0.1778)
							(mid 0.249642 -0.249642)
							(end 0.1778 -0.2794)
						)
					)
					(width 0)
					(fill yes)
				)
			)
		)
	)
	(footprint ""
		(layer "F.Cu")
		(at 212.217 -219.964 90)
		(property "Reference" "U176"
			(at 0 0 90)
			(layer "F.SilkS")
			(hide yes)
			(effects
				(font
					(size 1.27 1.27)
				)
			)
		)
		(property "Value" "SNLVC1G126DCKR-GP"
			(at -2.3368 -8.6868 90)
			(unlocked yes)
			(layer "F.Fab")
			(hide yes)
			(effects
				(font
					(size 1.016 1.016)
					(thickness 0.1524)
				)
			)
		)
		(property "Device Type" "SC70-5H44"
			(at -2.3114 -10.414 90)
			(unlocked yes)
			(layer "F.Fab")
			(hide yes)
			(effects
				(font
					(size 1.016 1.016)
					(thickness 0.1524)
				)
			)
		)
		(duplicate_pad_numbers_are_jumpers no)
		(fp_line
			(start 1.3843 -1.8034)
			(end 1.3843 -1.1176)
			(stroke
				(width 0.3302)
				(type default)
			)
			(layer "F.SilkS")
		)
		(fp_line
			(start 0.6604 -1.8034)
			(end 1.3843 -1.8034)
			(stroke
				(width 0.3302)
				(type default)
			)
			(layer "F.SilkS")
		)
		(fp_line
			(start 1.27 -1.7018)
			(end 1.27 1.7018)
			(stroke
				(width 0.1524)
				(type default)
			)
			(layer "F.SilkS")
		)
		(fp_line
			(start -1.27 -1.7018)
			(end 1.27 -1.7018)
			(stroke
				(width 0.1524)
				(type default)
			)
			(layer "F.SilkS")
		)
		(fp_line
			(start 1.27 1.7018)
			(end -1.27 1.7018)
			(stroke
				(width 0.1524)
				(type default)
			)
			(layer "F.SilkS")
		)
		(fp_line
			(start -1.27 1.7018)
			(end -1.27 -1.7018)
			(stroke
				(width 0.1524)
				(type default)
			)
			(layer "F.SilkS")
		)
		(fp_rect
			(start -1.524 1.9558)
			(end 1.524 -1.9558)
			(stroke
				(width 0)
				(type default)
			)
			(fill no)
			(layer "F.CrtYd")
		)
		(fp_poly
			(pts
				(xy -1.524 -1.9558) (xy 1.524 -1.9558) (xy 1.524 1.9558) (xy -1.524 1.9558)
			)
			(stroke
				(width 0)
				(type default)
			)
			(fill no)
			(layer "F.Fab")
		)
		(pad "1" smd rect
			(at 0.65024 -0.8255 90)
			(size 0.4064 1.2192)
			(layers "F.Cu" "F.Mask" "F.Paste")
			(net "OE_BMC_RSET")
		)
		(pad "2" smd rect
			(at 0 -0.8255 90)
			(size 0.4064 1.2192)
			(layers "F.Cu" "F.Mask" "F.Paste")
			(net "DP_BMC_CPU_RST_N_U177_OUT")
		)
		(pad "3" smd rect
			(at -0.65024 -0.8255 90)
			(size 0.4064 1.2192)
			(layers "F.Cu" "F.Mask" "F.Paste")
			(net "GND")
		)
		(pad "4" smd rect
			(at -0.65024 0.8255 90)
			(size 0.4064 1.2192)
			(layers "F.Cu" "F.Mask" "F.Paste")
			(net "CPU_RESET_N")
		)
		(pad "5" smd rect
			(at 0.65024 0.8255 90)
			(size 0.4064 1.2192)
			(layers "F.Cu" "F.Mask" "F.Paste")
			(net "P3V3_STBY")
		)
	)
	(footprint ""
		(layer "F.Cu")
		(at 101.74097 -76.454)
		(property "Reference" "SR923"
			(at 0 0 0)
			(layer "F.SilkS")
			(hide yes)
			(effects
				(font
					(size 1.27 1.27)
				)
			)
		)
		(property "Value" "0R2J-2-GP"
			(at 0.064008 -3.993896 0)
			(unlocked yes)
			(layer "F.Fab")
			(hide yes)
			(effects
				(font
					(size 1.016 1.016)
					(thickness 0.1524)
				)
			)
		)
		(property "Device Type" "R402H16"
			(at 0.064008 -5.517896 0)
			(unlocked yes)
			(layer "F.Fab")
			(hide yes)
			(effects
				(font
					(size 1.016 1.016)
					(thickness 0.1524)
				)
			)
		)
		(duplicate_pad_numbers_are_jumpers no)
		(fp_line
			(start -0.508 -0.9398)
			(end -0.508 0.9398)
			(stroke
				(width 0.1524)
				(type default)
			)
			(layer "F.SilkS")
		)
		(fp_line
			(start 0.508 -0.9398)
			(end -0.508 -0.9398)
			(stroke
				(width 0.1524)
				(type default)
			)
			(layer "F.SilkS")
		)
		(fp_rect
			(start -0.508 0.9398)
			(end 0.508 -0.9398)
			(stroke
				(width 0)
				(type default)
			)
			(fill no)
			(layer "F.CrtYd")
		)
		(fp_rect
			(start -0.508 0.9398)
			(end 0.508 -0.9398)
			(stroke
				(width 0)
				(type default)
			)
			(fill no)
			(layer "F.Fab")
		)
		(pad "1" smd custom
			(at 0 -0.4445)
			(size 0.1397 0.1397)
			(layers "F.Cu" "F.Mask" "F.Paste")
			(net "JTAG_EXP_TDO_R")
			(options
				(clearance outline)
				(anchor circle)
			)
			(primitives
				(gr_poly
					(pts
						(arc
							(start -0.1778 -0.2794)
							(mid -0.249642 -0.249642)
							(end -0.2794 -0.1778)
						)
						(arc
							(start -0.2794 0.1778)
							(mid -0.249642 0.249642)
							(end -0.1778 0.2794)
						)
						(arc
							(start 0.1778 0.2794)
							(mid 0.249642 0.249642)
							(end 0.2794 0.1778)
						)
						(arc
							(start 0.2794 -0.1778)
							(mid 0.249642 -0.249642)
							(end 0.1778 -0.2794)
						)
					)
					(width 0)
					(fill yes)
				)
			)
		)
		(pad "2" smd custom
			(at 0 0.4445)
			(size 0.1397 0.1397)
			(layers "F.Cu" "F.Mask" "F.Paste")
			(net "JTAG_EXP_TDO")
			(options
				(clearance outline)
				(anchor circle)
			)
			(primitives
				(gr_poly
					(pts
						(arc
							(start -0.1778 -0.2794)
							(mid -0.249642 -0.249642)
							(end -0.2794 -0.1778)
						)
						(arc
							(start -0.2794 0.1778)
							(mid -0.249642 0.249642)
							(end -0.1778 0.2794)
						)
						(arc
							(start 0.1778 0.2794)
							(mid 0.249642 0.249642)
							(end 0.2794 0.1778)
						)
						(arc
							(start 0.2794 -0.1778)
							(mid 0.249642 -0.249642)
							(end 0.1778 -0.2794)
						)
					)
					(width 0)
					(fill yes)
				)
			)
		)
	)
)
